#ISCELL
  pure_quanta quanta_title_block_c *
  *
#CELL
  pure_quanta socket4677_azif0045p001c01cs *
  page66_i16
#ISCELL
  logical_power universal_gnd *
  page66_i17
